# T6G (Grand Teton) — schematic netlist excerpt (pin names and nets, part order shuffled) for the footprints in the layout excerpt that follows; sources: Cadence DE-HDL packaged netlist, KiCad conversion of 04192023_DAF0TMB3IC0_F0TG_MB_C_brd_V02_OCP.brd

C128  Q_CAP  0.1UF 25V 10% X7R  pkg 0402  page 96 : A = P3V3_AUX ; B = GND
C2239  Q_CAP  22UF 4V 20% X6S  pkg C0402  page 69 : A = PVDDCR_CPU1_P0 ; B = GND
PC6586_2  Q_CAP  22UF 4V 20% X6S  pkg C0805  page 363 : A = P0V9_CPU0_RT_2D ; B = GND

(kicad_pcb
	(version 20260206)
	(generator "pcbnew")
	(generator_version "10.0")
	(general
		(thickness 1.6)
		(legacy_teardrops no)
	)
	(paper "A4")
	(title_block
		(title "04192023_DAF0TMB3IC0_F0TG_MB_C_brd_V02_OCP.brd")
		(comment 1 "Grand Teton / footprints 6921-6923 of 8354")
	)
	(layers
		(0 "F.Cu" signal "TOP")
		(4 "In1.Cu" signal "GND")
		(6 "In2.Cu" signal "IN1")
		(8 "In3.Cu" signal "GND1")
		(10 "In4.Cu" signal "IN2")
		(12 "In5.Cu" signal "GND2")
		(14 "In6.Cu" signal "IN3")
		(16 "In7.Cu" signal "GND3")
		(18 "In8.Cu" signal "VCC")
		(20 "In9.Cu" signal "VCC1")
		(22 "In10.Cu" signal "GND4")
		(24 "In11.Cu" signal "IN4")
		(26 "In12.Cu" signal "GND5")
		(28 "In13.Cu" signal "IN5")
		(30 "In14.Cu" signal "GND6")
		(32 "In15.Cu" signal "IN6")
		(34 "In16.Cu" signal "GND7")
		(2 "B.Cu" signal "BOTTOM")
		(9 "F.Adhes" user "F.Adhesive")
		(11 "B.Adhes" user "B.Adhesive")
		(13 "F.Paste" user "Package Geometry/Pastemask Top")
		(15 "B.Paste" user "Package Geometry/Pastemask Bottom")
		(5 "F.SilkS" user "Ref Des/Silkscreen Top")
		(7 "B.SilkS" user "Ref Des/Silkscreen Bottom")
		(1 "F.Mask" user "Board Geometry/Soldermask Top")
		(3 "B.Mask" user "Board Geometry/Soldermask Bottom")
		(17 "Dwgs.User" user "User.Drawings")
		(19 "Cmts.User" user "User.Comments")
		(21 "Eco1.User" user "User.Eco1")
		(23 "Eco2.User" user "User.Eco2")
		(25 "Edge.Cuts" user "Board Geometry/Outline")
		(27 "Margin" user)
		(31 "F.CrtYd" user "Package Geometry/Place Bound Top")
		(29 "B.CrtYd" user "Package Geometry/Place Bound Bottom")
		(35 "F.Fab" user "Ref Des/Assembly Top")
		(33 "B.Fab" user "Ref Des/Assembly Bottom")
	)
	(footprint ""
		(layer "B.Cu")
		(at 355.263958 -272.284952 180)
		(property "Reference" "C2239"
			(at 0 0 0)
			(layer "B.SilkS")
			(hide yes)
			(effects
				(font
					(size 1.27 1.27)
				)
				(justify mirror)
			)
		)
		(property "Value" ""
			(at 0 0 0)
			(layer "B.Fab")
			(effects
				(font
					(size 1.27 1.27)
				)
				(justify mirror)
			)
		)
		(duplicate_pad_numbers_are_jumpers no)
		(fp_line
			(start 0.7874 0.4064)
			(end 0.7874 -0.4064)
			(stroke
				(width 0.1524)
				(type default)
			)
			(layer "B.SilkS")
		)
		(fp_line
			(start 0.7874 -0.4064)
			(end -0.7874 -0.4064)
			(stroke
				(width 0.1524)
				(type default)
			)
			(layer "B.SilkS")
		)
		(fp_line
			(start -0.7874 0.4064)
			(end 0.7874 0.4064)
			(stroke
				(width 0.1524)
				(type default)
			)
			(layer "B.SilkS")
		)
		(fp_line
			(start -0.7874 -0.4064)
			(end -0.7874 0.4064)
			(stroke
				(width 0.1524)
				(type default)
			)
			(layer "B.SilkS")
		)
		(fp_line
			(start 0.67945 0.3048)
			(end 0.67945 -0.305054)
			(stroke
				(width 0.1)
				(type default)
			)
			(layer "B.Fab")
		)
		(fp_line
			(start 0.67945 -0.305054)
			(end 0.12065 -0.305054)
			(stroke
				(width 0.1)
				(type default)
			)
			(layer "B.Fab")
		)
		(fp_line
			(start 0.12065 0.3048)
			(end 0.67945 0.3048)
			(stroke
				(width 0.1)
				(type default)
			)
			(layer "B.Fab")
		)
		(fp_line
			(start 0.12065 0.2794)
			(end 0.12065 0.3048)
			(stroke
				(width 0.1)
				(type default)
			)
			(layer "B.Fab")
		)
		(fp_line
			(start 0.12065 -0.2794)
			(end -0.12065 -0.2794)
			(stroke
				(width 0.1)
				(type default)
			)
			(layer "B.Fab")
		)
		(fp_line
			(start 0.12065 -0.305054)
			(end 0.12065 -0.2794)
			(stroke
				(width 0.1)
				(type default)
			)
			(layer "B.Fab")
		)
		(fp_line
			(start -0.120396 0.3048)
			(end -0.120396 0.2794)
			(stroke
				(width 0.1)
				(type default)
			)
			(layer "B.Fab")
		)
		(fp_line
			(start -0.120396 0.2794)
			(end 0.12065 0.2794)
			(stroke
				(width 0.1)
				(type default)
			)
			(layer "B.Fab")
		)
		(fp_line
			(start -0.12065 -0.2794)
			(end -0.12065 -0.3048)
			(stroke
				(width 0.1)
				(type default)
			)
			(layer "B.Fab")
		)
		(fp_line
			(start -0.12065 -0.3048)
			(end -0.67945 -0.3048)
			(stroke
				(width 0.1)
				(type default)
			)
			(layer "B.Fab")
		)
		(fp_line
			(start -0.67945 0.3048)
			(end -0.120396 0.3048)
			(stroke
				(width 0.1)
				(type default)
			)
			(layer "B.Fab")
		)
		(fp_line
			(start -0.67945 -0.3048)
			(end -0.67945 0.3048)
			(stroke
				(width 0.1)
				(type default)
			)
			(layer "B.Fab")
		)
		(pad "1" smd circle
			(at 0.40005 0)
			(size 0 0)
			(layers "B.Cu" "B.Mask" "B.Paste")
			(net "PVDDCR_CPU1_P0")
		)
		(pad "2" smd circle
			(at -0.40005 0)
			(size 0 0)
			(layers "B.Cu" "B.Mask" "B.Paste")
			(net "GND")
		)
	)
	(footprint ""
		(layer "B.Cu")
		(at 438.344564 -193.99631)
		(property "Reference" "C128"
			(at 0 0 0)
			(layer "B.SilkS")
			(hide yes)
			(effects
				(font
					(size 1.27 1.27)
				)
				(justify mirror)
			)
		)
		(property "Value" ""
			(at 0 0 0)
			(layer "B.Fab")
			(effects
				(font
					(size 1.27 1.27)
				)
				(justify mirror)
			)
		)
		(duplicate_pad_numbers_are_jumpers no)
		(fp_line
			(start -0.7874 -0.4064)
			(end -0.7874 0.4064)
			(stroke
				(width 0.1524)
				(type default)
			)
			(layer "B.SilkS")
		)
		(fp_line
			(start -0.7874 0.4064)
			(end 0.7874 0.4064)
			(stroke
				(width 0.1524)
				(type default)
			)
			(layer "B.SilkS")
		)
		(fp_line
			(start 0.7874 -0.4064)
			(end -0.7874 -0.4064)
			(stroke
				(width 0.1524)
				(type default)
			)
			(layer "B.SilkS")
		)
		(fp_line
			(start 0.7874 0.4064)
			(end 0.7874 -0.4064)
			(stroke
				(width 0.1524)
				(type default)
			)
			(layer "B.SilkS")
		)
		(fp_line
			(start -0.67945 -0.3048)
			(end -0.67945 0.3048)
			(stroke
				(width 0.1)
				(type default)
			)
			(layer "B.Fab")
		)
		(fp_line
			(start -0.67945 0.3048)
			(end -0.120396 0.3048)
			(stroke
				(width 0.1)
				(type default)
			)
			(layer "B.Fab")
		)
		(fp_line
			(start -0.12065 -0.3048)
			(end -0.67945 -0.3048)
			(stroke
				(width 0.1)
				(type default)
			)
			(layer "B.Fab")
		)
		(fp_line
			(start -0.12065 -0.2794)
			(end -0.12065 -0.3048)
			(stroke
				(width 0.1)
				(type default)
			)
			(layer "B.Fab")
		)
		(fp_line
			(start -0.120396 0.2794)
			(end 0.12065 0.2794)
			(stroke
				(width 0.1)
				(type default)
			)
			(layer "B.Fab")
		)
		(fp_line
			(start -0.120396 0.3048)
			(end -0.120396 0.2794)
			(stroke
				(width 0.1)
				(type default)
			)
			(layer "B.Fab")
		)
		(fp_line
			(start 0.12065 -0.305054)
			(end 0.12065 -0.2794)
			(stroke
				(width 0.1)
				(type default)
			)
			(layer "B.Fab")
		)
		(fp_line
			(start 0.12065 -0.2794)
			(end -0.12065 -0.2794)
			(stroke
				(width 0.1)
				(type default)
			)
			(layer "B.Fab")
		)
		(fp_line
			(start 0.12065 0.2794)
			(end 0.12065 0.3048)
			(stroke
				(width 0.1)
				(type default)
			)
			(layer "B.Fab")
		)
		(fp_line
			(start 0.12065 0.3048)
			(end 0.67945 0.3048)
			(stroke
				(width 0.1)
				(type default)
			)
			(layer "B.Fab")
		)
		(fp_line
			(start 0.67945 -0.305054)
			(end 0.12065 -0.305054)
			(stroke
				(width 0.1)
				(type default)
			)
			(layer "B.Fab")
		)
		(fp_line
			(start 0.67945 0.3048)
			(end 0.67945 -0.305054)
			(stroke
				(width 0.1)
				(type default)
			)
			(layer "B.Fab")
		)
		(pad "1" smd circle
			(at 0.40005 0 180)
			(size 0 0)
			(layers "B.Cu" "B.Mask" "B.Paste")
			(net "P3V3_AUX")
		)
		(pad "2" smd circle
			(at -0.40005 0 180)
			(size 0 0)
			(layers "B.Cu" "B.Mask" "B.Paste")
			(net "GND")
		)
	)
	(footprint ""
		(layer "B.Cu")
		(at 450.431408 -389.600694 -90)
		(property "Reference" "PC6586_2"
			(at 0 0 90)
			(layer "B.SilkS")
			(hide yes)
			(effects
				(font
					(size 1.27 1.27)
				)
				(justify mirror)
			)
		)
		(property "Value" ""
			(at 0 0 90)
			(layer "B.Fab")
			(effects
				(font
					(size 1.27 1.27)
				)
				(justify mirror)
			)
		)
		(duplicate_pad_numbers_are_jumpers no)
		(fp_line
			(start -1.524 0.762)
			(end 1.524 0.762)
			(stroke
				(width 0.1524)
				(type default)
			)
			(layer "B.SilkS")
		)
		(fp_line
			(start 1.524 0.762)
			(end 1.524 -0.762)
			(stroke
				(width 0.1524)
				(type default)
			)
			(layer "B.SilkS")
		)
		(fp_line
			(start -1.524 -0.762)
			(end -1.524 0.762)
			(stroke
				(width 0.1524)
				(type default)
			)
			(layer "B.SilkS")
		)
		(fp_line
			(start 1.524 -0.762)
			(end -1.524 -0.762)
			(stroke
				(width 0.1524)
				(type default)
			)
			(layer "B.SilkS")
		)
		(fp_line
			(start -1.1049 0.724916)
			(end -1.1049 -0.724916)
			(stroke
				(width 0.1)
				(type default)
			)
			(layer "B.Fab")
		)
		(fp_line
			(start 1.1049 0.724916)
			(end -1.1049 0.724916)
			(stroke
				(width 0.1)
				(type default)
			)
			(layer "B.Fab")
		)
		(fp_line
			(start -1.1049 -0.724916)
			(end 1.1049 -0.724916)
			(stroke
				(width 0.1)
				(type default)
			)
			(layer "B.Fab")
		)
		(fp_line
			(start 1.1049 -0.724916)
			(end 1.1049 0.724916)
			(stroke
				(width 0.1)
				(type default)
			)
			(layer "B.Fab")
		)
		(pad "1" smd rect
			(at 0.889 0 270)
			(size 1.016 1.27)
			(layers "B.Cu" "B.Mask" "B.Paste")
			(net "P0V9_CPU0_RT_2D")
		)
		(pad "2" smd rect
			(at -0.889 0 270)
			(size 1.016 1.27)
			(layers "B.Cu" "B.Mask" "B.Paste")
			(net "GND")
		)
	)
)
